# S9S_MB_2U (Grand Teton) — schematic netlist excerpt (pin names and nets, part order shuffled) for the footprints in the layout excerpt that follows; sources: Cadence DE-HDL packaged netlist, KiCad conversion of 03242023_DA0F0TMBIJ0_F0T_Motherboard_J_brd_V01_OCP.brd

R4650  Q_RES  1K 1% EMPTY  pkg 0402LF  page 167 : A = FM_P2E_BUF2_EQA0 ; B = GND
C2343  Q_CAP  1000PF 50V 5% EMPTY  pkg 0402  page 146 : A = SWB_HSC_PWRGD_ISO ; B = GND

(kicad_pcb
	(version 20260206)
	(generator "pcbnew")
	(generator_version "10.0")
	(general
		(thickness 1.6)
		(legacy_teardrops no)
	)
	(paper "A4")
	(title_block
		(title "03242023_DA0F0TMBIJ0_F0T_Motherboard_J_brd_V01_OCP.brd")
		(comment 1 "Grand Teton / footprints 151-152 of 6105")
	)
	(layers
		(0 "F.Cu" signal "TOP")
		(4 "In1.Cu" signal "GND")
		(6 "In2.Cu" signal "IN1")
		(8 "In3.Cu" signal "GND1")
		(10 "In4.Cu" signal "IN2")
		(12 "In5.Cu" signal "GND2")
		(14 "In6.Cu" signal "IN3")
		(16 "In7.Cu" signal "GND3")
		(18 "In8.Cu" signal "VCC")
		(20 "In9.Cu" signal "VCC1")
		(22 "In10.Cu" signal "GND4")
		(24 "In11.Cu" signal "IN4")
		(26 "In12.Cu" signal "GND5")
		(28 "In13.Cu" signal "IN5")
		(30 "In14.Cu" signal "GND6")
		(32 "In15.Cu" signal "IN6")
		(34 "In16.Cu" signal "GND7")
		(2 "B.Cu" signal "BOTTOM")
		(9 "F.Adhes" user "F.Adhesive")
		(11 "B.Adhes" user "B.Adhesive")
		(13 "F.Paste" user "Package Geometry/Pastemask Top")
		(15 "B.Paste" user "Package Geometry/Pastemask Bottom")
		(5 "F.SilkS" user "Ref Des/Silkscreen Top")
		(7 "B.SilkS" user "Ref Des/Silkscreen Bottom")
		(1 "F.Mask" user "Board Geometry/Soldermask Top")
		(3 "B.Mask" user "Board Geometry/Soldermask Bottom")
		(17 "Dwgs.User" user "User.Drawings")
		(19 "Cmts.User" user "User.Comments")
		(21 "Eco1.User" user "User.Eco1")
		(23 "Eco2.User" user "User.Eco2")
		(25 "Edge.Cuts" user "Board Geometry/Outline")
		(27 "Margin" user)
		(31 "F.CrtYd" user "Package Geometry/Place Bound Top")
		(29 "B.CrtYd" user "Package Geometry/Place Bound Bottom")
		(35 "F.Fab" user "Ref Des/Assembly Top")
		(33 "B.Fab" user "Ref Des/Assembly Bottom")
	)
	(footprint ""
		(layer "F.Cu")
		(at 39.394892 -397.42491 90)
		(property "Reference" "R4650"
			(at 0 0 90)
			(layer "F.SilkS")
			(hide yes)
			(effects
				(font
					(size 1.27 1.27)
				)
			)
		)
		(property "Value" ""
			(at 0 0 90)
			(layer "F.Fab")
			(effects
				(font
					(size 1.27 1.27)
				)
			)
		)
		(duplicate_pad_numbers_are_jumpers no)
		(fp_line
			(start 0.7874 -0.4064)
			(end 0.7874 0.4064)
			(stroke
				(width 0.1524)
				(type default)
			)
			(layer "F.SilkS")
		)
		(fp_line
			(start -0.7874 -0.4064)
			(end 0.7874 -0.4064)
			(stroke
				(width 0.1524)
				(type default)
			)
			(layer "F.SilkS")
		)
		(fp_line
			(start 0.7874 0.4064)
			(end -0.7874 0.4064)
			(stroke
				(width 0.1524)
				(type default)
			)
			(layer "F.SilkS")
		)
		(fp_line
			(start -0.7874 0.4064)
			(end -0.7874 -0.4064)
			(stroke
				(width 0.1524)
				(type default)
			)
			(layer "F.SilkS")
		)
		(fp_line
			(start -0.12065 -0.305054)
			(end -0.12065 -0.2794)
			(stroke
				(width 0.1)
				(type default)
			)
			(layer "F.Fab")
		)
		(fp_line
			(start -0.67945 -0.305054)
			(end -0.12065 -0.305054)
			(stroke
				(width 0.1)
				(type default)
			)
			(layer "F.Fab")
		)
		(fp_line
			(start 0.67945 -0.3048)
			(end 0.67945 0.3048)
			(stroke
				(width 0.1)
				(type default)
			)
			(layer "F.Fab")
		)
		(fp_line
			(start 0.12065 -0.3048)
			(end 0.67945 -0.3048)
			(stroke
				(width 0.1)
				(type default)
			)
			(layer "F.Fab")
		)
		(fp_line
			(start 0.12065 -0.2794)
			(end 0.12065 -0.3048)
			(stroke
				(width 0.1)
				(type default)
			)
			(layer "F.Fab")
		)
		(fp_line
			(start -0.12065 -0.2794)
			(end 0.12065 -0.2794)
			(stroke
				(width 0.1)
				(type default)
			)
			(layer "F.Fab")
		)
		(fp_line
			(start 0.120396 0.2794)
			(end -0.12065 0.2794)
			(stroke
				(width 0.1)
				(type default)
			)
			(layer "F.Fab")
		)
		(fp_line
			(start -0.12065 0.2794)
			(end -0.12065 0.3048)
			(stroke
				(width 0.1)
				(type default)
			)
			(layer "F.Fab")
		)
		(fp_line
			(start 0.67945 0.3048)
			(end 0.120396 0.3048)
			(stroke
				(width 0.1)
				(type default)
			)
			(layer "F.Fab")
		)
		(fp_line
			(start 0.120396 0.3048)
			(end 0.120396 0.2794)
			(stroke
				(width 0.1)
				(type default)
			)
			(layer "F.Fab")
		)
		(fp_line
			(start -0.12065 0.3048)
			(end -0.67945 0.3048)
			(stroke
				(width 0.1)
				(type default)
			)
			(layer "F.Fab")
		)
		(fp_line
			(start -0.67945 0.3048)
			(end -0.67945 -0.305054)
			(stroke
				(width 0.1)
				(type default)
			)
			(layer "F.Fab")
		)
		(pad "1" smd circle
			(at -0.40005 0 90)
			(size 0 0)
			(layers "F.Cu" "F.Mask" "F.Paste")
			(net "FM_P2E_BUF2_EQA0")
		)
		(pad "2" smd circle
			(at 0.40005 0 90)
			(size 0 0)
			(layers "F.Cu" "F.Mask" "F.Paste")
			(net "GND")
		)
	)
	(footprint ""
		(layer "F.Cu")
		(at 356.616 -414.111948 180)
		(property "Reference" "C2343"
			(at 0 0 180)
			(layer "F.SilkS")
			(hide yes)
			(effects
				(font
					(size 1.27 1.27)
				)
			)
		)
		(property "Value" ""
			(at 0 0 180)
			(layer "F.Fab")
			(effects
				(font
					(size 1.27 1.27)
				)
			)
		)
		(duplicate_pad_numbers_are_jumpers no)
		(fp_line
			(start 0.7874 0.4064)
			(end -0.7874 0.4064)
			(stroke
				(width 0.1524)
				(type default)
			)
			(layer "F.SilkS")
		)
		(fp_line
			(start 0.7874 -0.4064)
			(end 0.7874 0.4064)
			(stroke
				(width 0.1524)
				(type default)
			)
			(layer "F.SilkS")
		)
		(fp_line
			(start -0.7874 0.4064)
			(end -0.7874 -0.4064)
			(stroke
				(width 0.1524)
				(type default)
			)
			(layer "F.SilkS")
		)
		(fp_line
			(start -0.7874 -0.4064)
			(end 0.7874 -0.4064)
			(stroke
				(width 0.1524)
				(type default)
			)
			(layer "F.SilkS")
		)
		(fp_line
			(start 0.67945 0.3048)
			(end 0.120396 0.3048)
			(stroke
				(width 0.1)
				(type default)
			)
			(layer "F.Fab")
		)
		(fp_line
			(start 0.67945 -0.3048)
			(end 0.67945 0.3048)
			(stroke
				(width 0.1)
				(type default)
			)
			(layer "F.Fab")
		)
		(fp_line
			(start 0.12065 -0.2794)
			(end 0.12065 -0.3048)
			(stroke
				(width 0.1)
				(type default)
			)
			(layer "F.Fab")
		)
		(fp_line
			(start 0.12065 -0.3048)
			(end 0.67945 -0.3048)
			(stroke
				(width 0.1)
				(type default)
			)
			(layer "F.Fab")
		)
		(fp_line
			(start 0.120396 0.3048)
			(end 0.120396 0.2794)
			(stroke
				(width 0.1)
				(type default)
			)
			(layer "F.Fab")
		)
		(fp_line
			(start 0.120396 0.2794)
			(end -0.12065 0.2794)
			(stroke
				(width 0.1)
				(type default)
			)
			(layer "F.Fab")
		)
		(fp_line
			(start -0.12065 0.3048)
			(end -0.67945 0.3048)
			(stroke
				(width 0.1)
				(type default)
			)
			(layer "F.Fab")
		)
		(fp_line
			(start -0.12065 0.2794)
			(end -0.12065 0.3048)
			(stroke
				(width 0.1)
				(type default)
			)
			(layer "F.Fab")
		)
		(fp_line
			(start -0.12065 -0.2794)
			(end 0.12065 -0.2794)
			(stroke
				(width 0.1)
				(type default)
			)
			(layer "F.Fab")
		)
		(fp_line
			(start -0.12065 -0.305054)
			(end -0.12065 -0.2794)
			(stroke
				(width 0.1)
				(type default)
			)
			(layer "F.Fab")
		)
		(fp_line
			(start -0.67945 0.3048)
			(end -0.67945 -0.305054)
			(stroke
				(width 0.1)
				(type default)
			)
			(layer "F.Fab")
		)
		(fp_line
			(start -0.67945 -0.305054)
			(end -0.12065 -0.305054)
			(stroke
				(width 0.1)
				(type default)
			)
			(layer "F.Fab")
		)
		(pad "1" smd circle
			(at -0.40005 0 180)
			(size 0 0)
			(layers "F.Cu" "F.Mask" "F.Paste")
			(net "SWB_HSC_PWRGD_ISO")
		)
		(pad "2" smd circle
			(at 0.40005 0 180)
			(size 0 0)
			(layers "F.Cu" "F.Mask" "F.Paste")
			(net "GND")
		)
	)
)
